# BASEBOARD_FAB2 (Tioga Pass) — schematic netlist excerpt (pin names and nets, part order shuffled) for the footprints in the layout excerpt that follows; sources: Cadence DE-HDL packaged netlist, KiCad conversion of Wiwynn_Tioga_Pass_MB.brd

C4A3  CAP  1000PF 50V 10% X7R  pkg 0402LF  page 230 : A = PWRGD_PVTT_KLM_CPU1_R ; B = GND
C3C1  CAP_A  1.0UF 6.3V 10% X6S  pkg 0402V  page 193 : A = PVCCIOMCP_CPU1 ; B = GND
R8E3  RES  4.75K 1% CHIP  pkg 0402  page 133 : A = P3V3_STBY ; B = FM_TPM_PRES_N

(kicad_pcb
	(version 20260206)
	(generator "pcbnew")
	(generator_version "10.0")
	(general
		(thickness 1.6)
		(legacy_teardrops no)
	)
	(paper "A4")
	(title_block
		(title "Wiwynn_Tioga_Pass_MB.brd")
		(comment 1 "Tioga Pass / footprints 728-730 of 4770")
	)
	(layers
		(0 "F.Cu" signal "TOP")
		(4 "In1.Cu" signal "L2GND")
		(6 "In2.Cu" signal "L3")
		(8 "In3.Cu" signal "L4GND")
		(10 "In4.Cu" signal "L5")
		(12 "In5.Cu" signal "L6GND")
		(14 "In6.Cu" signal "L7VCC")
		(16 "In7.Cu" signal "L8VCC")
		(18 "In8.Cu" signal "L9GND")
		(20 "In9.Cu" signal "L10")
		(22 "In10.Cu" signal "L11GND")
		(24 "In11.Cu" signal "L12")
		(26 "In12.Cu" signal "L13GND")
		(2 "B.Cu" signal "BOTTOM")
		(9 "F.Adhes" user "F.Adhesive")
		(11 "B.Adhes" user "B.Adhesive")
		(13 "F.Paste" user "Package Geometry/Pastemask Top")
		(15 "B.Paste" user "Package Geometry/Pastemask Bottom")
		(5 "F.SilkS" user "Ref Des/Silkscreen Top")
		(7 "B.SilkS" user "Ref Des/Silkscreen Bottom")
		(1 "F.Mask" user "Board Geometry/Soldermask Top")
		(3 "B.Mask" user "Board Geometry/Soldermask Bottom")
		(17 "Dwgs.User" user "User.Drawings")
		(19 "Cmts.User" user "User.Comments")
		(21 "Eco1.User" user "User.Eco1")
		(23 "Eco2.User" user "User.Eco2")
		(25 "Edge.Cuts" user "Board Geometry/Outline")
		(27 "Margin" user)
		(31 "F.CrtYd" user "Package Geometry/Place Bound Top")
		(29 "B.CrtYd" user "Package Geometry/Place Bound Bottom")
		(35 "F.Fab" user "Ref Des/Assembly Top")
		(33 "B.Fab" user "Ref Des/Assembly Bottom")
	)
	(footprint ""
		(layer "F.Cu")
		(at 386.08 -87.3125 180)
		(property "Reference" "R8E3"
			(at 0 0 180)
			(layer "F.SilkS")
			(hide yes)
			(effects
				(font
					(size 1.27 1.27)
				)
			)
		)
		(property "Value" ""
			(at 0 0 180)
			(layer "F.Fab")
			(effects
				(font
					(size 1.27 1.27)
				)
			)
		)
		(duplicate_pad_numbers_are_jumpers no)
		(fp_poly
			(pts
				(xy -0.2794 -0.1016) (xy 0.2794 -0.1016) (xy 0.2794 0.9906) (xy -0.2794 0.9906)
			)
			(stroke
				(width 0)
				(type default)
			)
			(fill no)
			(layer "F.CrtYd")
		)
		(fp_line
			(start 0.2794 0.9906)
			(end 0.2794 -0.1016)
			(stroke
				(width 0.1)
				(type default)
			)
			(layer "F.Fab")
		)
		(fp_line
			(start 0.2794 -0.1016)
			(end -0.2794 -0.1016)
			(stroke
				(width 0.1)
				(type default)
			)
			(layer "F.Fab")
		)
		(fp_line
			(start -0.2794 0.9906)
			(end 0.2794 0.9906)
			(stroke
				(width 0.1)
				(type default)
			)
			(layer "F.Fab")
		)
		(fp_line
			(start -0.2794 -0.1016)
			(end -0.2794 0.9906)
			(stroke
				(width 0.1)
				(type default)
			)
			(layer "F.Fab")
		)
		(pad "1" smd rect
			(at 0 0 180)
			(size 0.508 0.508)
			(layers "F.Cu" "F.Mask" "F.Paste")
			(net "P3V3_STBY")
		)
		(pad "2" smd rect
			(at 0 0.889 180)
			(size 0.508 0.508)
			(layers "F.Cu" "F.Mask" "F.Paste")
			(net "FM_TPM_PRES_N")
		)
		(zone
			(layer "F.Cu")
			(hatch none 0.5)
			(connect_pads
				(clearance 0)
			)
			(min_thickness 0.25)
			(keepout
				(tracks not_allowed)
				(vias allowed)
				(pads allowed)
				(copperpour not_allowed)
				(footprints allowed)
			)
			(placement
				(enabled no)
				(sheetname "")
			)
			(fill
				(thermal_gap 0.5)
				(thermal_bridge_width 0.5)
				(island_removal_mode 0)
			)
			(polygon
				(pts
					(xy 386.334 -87.9475) (xy 385.826 -87.9475) (xy 385.826 -87.5665) (xy 386.334 -87.5665)
				)
			)
		)
		(zone
			(layer "F.Cu")
			(hatch none 0.5)
			(connect_pads
				(clearance 0)
			)
			(min_thickness 0.25)
			(keepout
				(tracks allowed)
				(vias not_allowed)
				(pads allowed)
				(copperpour not_allowed)
				(footprints allowed)
			)
			(placement
				(enabled no)
				(sheetname "")
			)
			(fill
				(thermal_gap 0.5)
				(thermal_bridge_width 0.5)
				(island_removal_mode 0)
			)
			(polygon
				(pts
					(xy 386.334 -87.5665) (xy 385.826 -87.5665) (xy 385.826 -87.9475) (xy 386.334 -87.9475)
				)
			)
		)
	)
	(footprint ""
		(layer "F.Cu")
		(at 161.798 -104.14)
		(property "Reference" "C3C1"
			(at 0 0 0)
			(layer "F.SilkS")
			(hide yes)
			(effects
				(font
					(size 1.27 1.27)
				)
			)
		)
		(property "Value" ""
			(at 0 0 0)
			(layer "F.Fab")
			(effects
				(font
					(size 1.27 1.27)
				)
			)
		)
		(duplicate_pad_numbers_are_jumpers no)
		(fp_poly
			(pts
				(xy 0.3048 -0.1016) (xy 0.3048 0.9906) (xy -0.3048 0.9906) (xy -0.3048 -0.1016)
			)
			(stroke
				(width 0)
				(type default)
			)
			(fill no)
			(layer "F.CrtYd")
		)
		(fp_line
			(start -0.3048 -0.1016)
			(end -0.3048 0.9906)
			(stroke
				(width 0.1)
				(type default)
			)
			(layer "F.Fab")
		)
		(fp_line
			(start -0.3048 0.9906)
			(end 0.3048 0.9906)
			(stroke
				(width 0.1)
				(type default)
			)
			(layer "F.Fab")
		)
		(fp_line
			(start 0.3048 -0.1016)
			(end -0.3048 -0.1016)
			(stroke
				(width 0.1)
				(type default)
			)
			(layer "F.Fab")
		)
		(fp_line
			(start 0.3048 0.9906)
			(end 0.3048 -0.1016)
			(stroke
				(width 0.1)
				(type default)
			)
			(layer "F.Fab")
		)
		(pad "1" smd rect
			(at 0 0)
			(size 0.508 0.508)
			(layers "F.Cu" "F.Mask" "F.Paste")
			(net "PVCCIOMCP_CPU1")
		)
		(pad "2" smd rect
			(at 0 0.889)
			(size 0.508 0.508)
			(layers "F.Cu" "F.Mask" "F.Paste")
			(net "GND")
		)
		(zone
			(layer "F.Cu")
			(hatch none 0.5)
			(connect_pads
				(clearance 0)
			)
			(min_thickness 0.25)
			(keepout
				(tracks allowed)
				(vias not_allowed)
				(pads allowed)
				(copperpour not_allowed)
				(footprints allowed)
			)
			(placement
				(enabled no)
				(sheetname "")
			)
			(fill
				(thermal_gap 0.5)
				(thermal_bridge_width 0.5)
				(island_removal_mode 0)
			)
			(polygon
				(pts
					(xy 161.544 -103.886) (xy 162.052 -103.886) (xy 162.052 -103.505) (xy 161.544 -103.505)
				)
			)
		)
		(zone
			(layer "F.Cu")
			(hatch none 0.5)
			(connect_pads
				(clearance 0)
			)
			(min_thickness 0.25)
			(keepout
				(tracks not_allowed)
				(vias allowed)
				(pads allowed)
				(copperpour not_allowed)
				(footprints allowed)
			)
			(placement
				(enabled no)
				(sheetname "")
			)
			(fill
				(thermal_gap 0.5)
				(thermal_bridge_width 0.5)
				(island_removal_mode 0)
			)
			(polygon
				(pts
					(xy 161.544 -103.505) (xy 162.052 -103.505) (xy 162.052 -103.886) (xy 161.544 -103.886)
				)
			)
		)
	)
	(footprint ""
		(layer "F.Cu")
		(at 172.18152 -150.25624 -90)
		(property "Reference" "C4A3"
			(at 0 0 270)
			(layer "F.SilkS")
			(hide yes)
			(effects
				(font
					(size 1.27 1.27)
				)
			)
		)
		(property "Value" ""
			(at 0 0 270)
			(layer "F.Fab")
			(effects
				(font
					(size 1.27 1.27)
				)
			)
		)
		(duplicate_pad_numbers_are_jumpers no)
		(fp_rect
			(start 0.3048 0.9906)
			(end -0.3048 -0.1016)
			(stroke
				(width 0)
				(type default)
			)
			(fill no)
			(layer "F.CrtYd")
		)
		(fp_line
			(start -0.3048 0.9906)
			(end 0.3048 0.9906)
			(stroke
				(width 0.1)
				(type default)
			)
			(layer "F.Fab")
		)
		(fp_line
			(start 0.3048 0.9906)
			(end 0.3048 -0.1016)
			(stroke
				(width 0.1)
				(type default)
			)
			(layer "F.Fab")
		)
		(fp_line
			(start -0.3048 -0.1016)
			(end -0.3048 0.9906)
			(stroke
				(width 0.1)
				(type default)
			)
			(layer "F.Fab")
		)
		(fp_line
			(start 0.3048 -0.1016)
			(end -0.3048 -0.1016)
			(stroke
				(width 0.1)
				(type default)
			)
			(layer "F.Fab")
		)
		(pad "1" smd rect
			(at 0 0 270)
			(size 0.508 0.508)
			(layers "F.Cu" "F.Mask" "F.Paste")
			(net "PWRGD_PVTT_KLM_CPU1_R")
		)
		(pad "2" smd rect
			(at 0 0.889 270)
			(size 0.508 0.508)
			(layers "F.Cu" "F.Mask" "F.Paste")
			(net "GND")
		)
		(zone
			(layer "F.Cu")
			(hatch none 0.5)
			(connect_pads
				(clearance 0)
			)
			(min_thickness 0.25)
			(keepout
				(tracks not_allowed)
				(vias allowed)
				(pads allowed)
				(copperpour not_allowed)
				(footprints allowed)
			)
			(placement
				(enabled no)
				(sheetname "")
			)
			(fill
				(thermal_gap 0.5)
				(thermal_bridge_width 0.5)
				(island_removal_mode 0)
			)
			(polygon
				(pts
					(xy 171.54652 -150.00224) (xy 171.92752 -150.00224) (xy 171.92752 -150.51024) (xy 171.54652 -150.51024)
				)
			)
		)
		(zone
			(layer "F.Cu")
			(hatch none 0.5)
			(connect_pads
				(clearance 0)
			)
			(min_thickness 0.25)
			(keepout
				(tracks allowed)
				(vias not_allowed)
				(pads allowed)
				(copperpour not_allowed)
				(footprints allowed)
			)
			(placement
				(enabled no)
				(sheetname "")
			)
			(fill
				(thermal_gap 0.5)
				(thermal_bridge_width 0.5)
				(island_removal_mode 0)
			)
			(polygon
				(pts
					(xy 171.54652 -150.00224) (xy 171.92752 -150.00224) (xy 171.92752 -150.51024) (xy 171.54652 -150.51024)
				)
			)
		)
	)
)
